(kicad_pcb
	(version 20221018)
	(generator pcbnew)
	(general
    (thickness 1.518)
  )
	(paper "A4")
	(title_block
    (title "Kria K26 Devboard")
    (date "2024-03-26")
    (rev "1.2.5")
    (comment 1 "www.antmicro.com")
    (comment 2 "Antmicro Ltd.")
		(comment 9 "footprints 342-351 of 660")
	)
	(layers
    (0 "F.Cu" mixed)
    (1 "In1.Cu" power)
    (2 "In2.Cu" mixed)
    (3 "In3.Cu" power)
    (4 "In4.Cu" mixed)
    (5 "In5.Cu" power)
    (6 "In6.Cu" mixed)
    (31 "B.Cu" power)
    (32 "B.Adhes" user "B.Adhesive")
    (33 "F.Adhes" user "F.Adhesive")
    (34 "B.Paste" user)
    (35 "F.Paste" user)
    (36 "B.SilkS" user "B.Silkscreen")
    (37 "F.SilkS" user "F.Silkscreen")
    (38 "B.Mask" user)
    (39 "F.Mask" user)
    (40 "Dwgs.User" user "User.Drawings")
    (41 "Cmts.User" user "User.Comments")
    (42 "Eco1.User" user "User.Eco1")
    (43 "Eco2.User" user "User.Eco2")
    (44 "Edge.Cuts" user)
    (45 "Margin" user)
    (46 "B.CrtYd" user "B.Courtyard")
    (47 "F.CrtYd" user "F.Courtyard")
    (48 "B.Fab" user)
    (49 "F.Fab" user)
  )
	(footprint "kria-k26-devboard-footprints:R_0402_1005Metric" (layer "F.Cu")
    (at 173.25 132.639999 -90)
    (descr "Resistor SMD 0402")
    (tags "resistor SMD 0402")
    (property "Author" "Antmicro")
    (property "License" "Apache-2.0")
    (property "MPN" "CR0402-FX-1002GLF")
    (property "Manufacturer" "Bourns")
    (property "Sheetfile" "dc-dc-conventers.kicad_sch")
    (property "Sheetname" "DC/DC conventers")
    (property "Tolerance" "1%")
    (property "Val" "10k")
    (property "ki_description" "10k resistor in 0402 package with 1% tolerance")
    (attr smd)
    (fp_text reference "R132" (at 1.330001 -1.21 -90) (layer "F.SilkS")
        (effects (font (size 0.7 0.7) (thickness 0.15)) (justify left bottom))
    )
    (fp_text value "R_10k_0402" (at 0 1.4 -90) (layer "F.Fab") hide
        (effects (font (size 0.7 0.7) (thickness 0.15)) (justify left bottom))
    )
    (fp_text user "${REFERENCE}" (at -0.95 3.168 -90) (layer "F.Fab") hide
        (effects (font (size 0.7 0.7) (thickness 0.15)) (justify left bottom))
    )
    (fp_text user "License: Apache-2.0" (at -0.95 5.169 -90) (layer "F.Fab") hide
        (effects (font (size 0.7 0.7) (thickness 0.15)) (justify left bottom))
    )
    (fp_text user "Author: Antmicro" (at -0.95 4.169 -90) (layer "F.Fab") hide
        (effects (font (size 0.7 0.7) (thickness 0.15)) (justify left bottom))
    )
    (fp_rect (start -0.93 -0.47) (end 0.93 0.47)
      (stroke (width 0.05) (type solid)) (fill none) (layer "F.CrtYd"))
    (fp_rect (start -0.5 -0.25) (end 0.5 0.25)
      (stroke (width 0.15) (type solid)) (fill none) (layer "F.Fab"))
    (pad "1" smd roundrect (at -0.485 0 270) (size 0.59 0.64) (layers "F.Cu" "F.Paste" "F.Mask") (roundrect_rratio 0.25)
      (net 688 "Net-(U49-FB)") (pintype "passive"))
    (pad "2" smd roundrect (at 0.485 0 270) (size 0.59 0.64) (layers "F.Cu" "F.Paste" "F.Mask") (roundrect_rratio 0.25)
      (net 1 "GND") (pintype "passive"))
  )
	(footprint "kria-k26-devboard-footprints:R_0402_1005Metric" (layer "F.Cu")
    (at 171.380001 132.375)
    (descr "Resistor SMD 0402")
    (tags "resistor SMD 0402")
    (property "Author" "Antmicro")
    (property "License" "Apache-2.0")
    (property "MPN" "CR0402-FX-3162GLF")
    (property "Manufacturer" "Bourns")
    (property "Sheetfile" "dc-dc-conventers.kicad_sch")
    (property "Sheetname" "DC/DC conventers")
    (property "Tolerance" "1%")
    (property "Val" "31k6")
    (property "ki_description" "31k6 resistor in 0402 package with 1% tolerance")
    (attr smd)
    (fp_text reference "R131" (at 1.049999 2.325) (layer "F.SilkS")
        (effects (font (size 0.7 0.7) (thickness 0.15)) (justify left bottom))
    )
    (fp_text value "R_31k6_0402" (at 0 1.4) (layer "F.Fab") hide
        (effects (font (size 0.7 0.7) (thickness 0.15)) (justify left bottom))
    )
    (fp_text user "License: Apache-2.0" (at -0.95 5.169) (layer "F.Fab") hide
        (effects (font (size 0.7 0.7) (thickness 0.15)) (justify left bottom))
    )
    (fp_text user "${REFERENCE}" (at -0.95 3.168) (layer "F.Fab") hide
        (effects (font (size 0.7 0.7) (thickness 0.15)) (justify left bottom))
    )
    (fp_text user "Author: Antmicro" (at -0.95 4.169) (layer "F.Fab") hide
        (effects (font (size 0.7 0.7) (thickness 0.15)) (justify left bottom))
    )
    (fp_rect (start -0.93 -0.47) (end 0.93 0.47)
      (stroke (width 0.05) (type solid)) (fill none) (layer "F.CrtYd"))
    (fp_rect (start -0.5 -0.25) (end 0.5 0.25)
      (stroke (width 0.15) (type solid)) (fill none) (layer "F.Fab"))
    (pad "1" smd roundrect (at -0.485 0) (size 0.59 0.64) (layers "F.Cu" "F.Paste" "F.Mask") (roundrect_rratio 0.25)
      (net 765 "/Power Supply/DC/DC conventers/PS_3V3_OUT") (pintype "passive"))
    (pad "2" smd roundrect (at 0.485 0) (size 0.59 0.64) (layers "F.Cu" "F.Paste" "F.Mask") (roundrect_rratio 0.25)
      (net 688 "Net-(U49-FB)") (pintype "passive"))
  )
	(footprint "kria-k26-devboard-footprints:TP_SMD_0.75mm" (layer "F.Cu")
    (at 153.265 118.65)
    (property "Author" "Antmicro")
    (property "License" "Apache-2.0")
    (property "MPN" "")
    (property "Manufacturer" "")
    (property "Sheetfile" "debug.kicad_sch")
    (property "Sheetname" "Debug and JTAG")
    (property "ki_description" "Test Point 0.75mm")
    (attr exclude_from_pos_files)
    (fp_text reference "TP24" (at 1.255 1.19 90) (layer "F.SilkS")
        (effects (font (size 0.7 0.7) (thickness 0.15)) (justify left bottom))
    )
    (fp_text value "TP_0.75mm_SMD" (at 0 1.2) (layer "F.Fab") hide
        (effects (font (size 0.7 0.7) (thickness 0.15)) (justify left bottom))
    )
    (fp_text user "${REFERENCE}" (at -0.4 2.7) (layer "F.Fab") hide
        (effects (font (size 0.7 0.7) (thickness 0.15)) (justify left bottom))
    )
    (fp_text user "Author: Antmicro" (at -0.4 3.901) (layer "F.Fab") hide
        (effects (font (size 0.7 0.7) (thickness 0.15)) (justify left bottom))
    )
    (fp_text user "License: Apache-2.0" (at -0.4 5.101) (layer "F.Fab") hide
        (effects (font (size 0.7 0.7) (thickness 0.15)) (justify left bottom))
    )
    (pad "1" smd circle (at 0 0) (size 0.75 0.75) (layers "F.Cu" "F.Mask")
      (net 132 "/Debug and JTAG/USB_1V2") (pinfunction "1") (pintype "passive"))
  )
	(footprint "kria-k26-devboard-footprints:TP_SMD_0.75mm" (layer "F.Cu")
    (at 153.3 123.5)
    (property "Author" "Antmicro")
    (property "License" "Apache-2.0")
    (property "MPN" "")
    (property "Manufacturer" "")
    (property "Sheetfile" "debug.kicad_sch")
    (property "Sheetname" "Debug and JTAG")
    (property "ki_description" "Test Point 0.75mm")
    (attr exclude_from_pos_files)
    (fp_text reference "TP26" (at 1.19 1.11 90) (layer "F.SilkS")
        (effects (font (size 0.7 0.7) (thickness 0.15)) (justify left bottom))
    )
    (fp_text value "TP_0.75mm_SMD" (at 0 1.2) (layer "F.Fab") hide
        (effects (font (size 0.7 0.7) (thickness 0.15)) (justify left bottom))
    )
    (fp_text user "${REFERENCE}" (at -0.4 2.7) (layer "F.Fab") hide
        (effects (font (size 0.7 0.7) (thickness 0.15)) (justify left bottom))
    )
    (fp_text user "License: Apache-2.0" (at -0.4 5.101) (layer "F.Fab") hide
        (effects (font (size 0.7 0.7) (thickness 0.15)) (justify left bottom))
    )
    (fp_text user "Author: Antmicro" (at -0.4 3.901) (layer "F.Fab") hide
        (effects (font (size 0.7 0.7) (thickness 0.15)) (justify left bottom))
    )
    (pad "1" smd circle (at 0 0) (size 0.75 0.75) (layers "F.Cu" "F.Mask")
      (net 134 "/Debug and JTAG/VREGIN") (pinfunction "1") (pintype "passive"))
  )
	(footprint "kria-k26-devboard-footprints:C_0402_1005Metric" (layer "F.Cu")
    (at 185.6 135.825 -90)
    (descr "Capacitor SMD 0402")
    (tags "capacitor SMD 0402")
    (property "Author" "Antmicro")
    (property "Dielectric" "X5R")
    (property "License" "Apache-2.0")
    (property "MPN" "GRM155R61H104KE14D")
    (property "Manufacturer" "Murata")
    (property "Sheetfile" "dc-dc-conventers.kicad_sch")
    (property "Sheetname" "DC/DC conventers")
    (property "Val" "100n")
    (property "Voltage" "50V")
    (property "ki_description" " ")
    (attr smd)
    (fp_text reference "C222" (at -6.225 1.65 180) (layer "F.SilkS")
        (effects (font (size 0.7 0.7) (thickness 0.15)) (justify left bottom))
    )
    (fp_text value "C_100n_0402" (at 0 1.4 -90) (layer "F.Fab") hide
        (effects (font (size 0.7 0.7) (thickness 0.15)) (justify left bottom))
    )
    (fp_text user "${REFERENCE}" (at -0.932 3.168 -90) (layer "F.Fab") hide
        (effects (font (size 0.7 0.7) (thickness 0.15)) (justify left bottom))
    )
    (fp_text user "Author: Antmicro" (at -0.932 4.17 -90) (layer "F.Fab") hide
        (effects (font (size 0.7 0.7) (thickness 0.15)) (justify left bottom))
    )
    (fp_text user "License: Apache-2.0" (at -0.932 5.17 -90) (layer "F.Fab") hide
        (effects (font (size 0.7 0.7) (thickness 0.15)) (justify left bottom))
    )
    (fp_rect (start -0.94 -0.47) (end 0.94 0.47)
      (stroke (width 0.05) (type solid)) (fill none) (layer "F.CrtYd"))
    (fp_rect (start -0.499 -0.249) (end 0.499 0.249)
      (stroke (width 0.15) (type solid)) (fill none) (layer "F.Fab"))
    (pad "1" smd roundrect (at -0.484 0 270) (size 0.59 0.64) (layers "F.Cu" "F.Paste" "F.Mask") (roundrect_rratio 0.25)
      (net 326 "Net-(U55-BST)") (pintype "passive"))
    (pad "2" smd roundrect (at 0.484 0 270) (size 0.59 0.64) (layers "F.Cu" "F.Paste" "F.Mask") (roundrect_rratio 0.25)
      (net 316 "/Power Supply/DC/DC conventers/SW_PL_1V2") (pintype "passive"))
  )
	(footprint "kria-k26-devboard-footprints:TP_SMD_0.75mm" (layer "F.Cu")
    (at 165.725 128.35)
    (property "Author" "Antmicro")
    (property "License" "Apache-2.0")
    (property "MPN" "")
    (property "Manufacturer" "")
    (property "Sheetfile" "dc-dc-conventers.kicad_sch")
    (property "Sheetname" "DC/DC conventers")
    (property "ki_description" "Test Point 0.75mm")
    (attr exclude_from_pos_files)
    (fp_text reference "TP50" (at -3.495 -1.65 90) (layer "F.SilkS")
        (effects (font (size 0.7 0.7) (thickness 0.15)) (justify left bottom))
    )
    (fp_text value "TP_0.75mm_SMD" (at 0 1.2) (layer "F.Fab") hide
        (effects (font (size 0.7 0.7) (thickness 0.15)) (justify left bottom))
    )
    (fp_text user "Author: Antmicro" (at -0.4 3.901) (layer "F.Fab") hide
        (effects (font (size 0.7 0.7) (thickness 0.15)) (justify left bottom))
    )
    (fp_text user "License: Apache-2.0" (at -0.4 5.101) (layer "F.Fab") hide
        (effects (font (size 0.7 0.7) (thickness 0.15)) (justify left bottom))
    )
    (fp_text user "${REFERENCE}" (at -0.4 2.7) (layer "F.Fab") hide
        (effects (font (size 0.7 0.7) (thickness 0.15)) (justify left bottom))
    )
    (pad "1" smd circle (at 0 0) (size 0.75 0.75) (layers "F.Cu" "F.Mask")
      (net 773 "/Power Supply/DC/DC conventers/SOM_5V_OUT") (pinfunction "1") (pintype "passive"))
  )
	(footprint "kria-k26-devboard-footprints:TP_SMD_0.75mm" (layer "F.Cu")
    (at 149.75 79.0008)
    (property "Author" "Antmicro")
    (property "License" "Apache-2.0")
    (property "MPN" "")
    (property "Manufacturer" "")
    (property "Sheetfile" "dc-dc-conventers.kicad_sch")
    (property "Sheetname" "DC/DC conventers")
    (property "ki_description" "Test Point 0.75mm")
    (attr exclude_from_pos_files)
    (fp_text reference "TP51" (at -1.3 1.2192) (layer "F.SilkS")
        (effects (font (size 0.7 0.7) (thickness 0.15)) (justify left bottom))
    )
    (fp_text value "TP_0.75mm_SMD" (at 0 1.2) (layer "F.Fab") hide
        (effects (font (size 0.7 0.7) (thickness 0.15)) (justify left bottom))
    )
    (fp_text user "Author: Antmicro" (at -0.4 3.901) (layer "F.Fab") hide
        (effects (font (size 0.7 0.7) (thickness 0.15)) (justify left bottom))
    )
    (fp_text user "${REFERENCE}" (at -0.4 2.7) (layer "F.Fab") hide
        (effects (font (size 0.7 0.7) (thickness 0.15)) (justify left bottom))
    )
    (fp_text user "License: Apache-2.0" (at -0.4 5.101) (layer "F.Fab") hide
        (effects (font (size 0.7 0.7) (thickness 0.15)) (justify left bottom))
    )
    (pad "1" smd circle (at 0 0) (size 0.75 0.75) (layers "F.Cu" "F.Mask")
      (net 772 "/Power Supply/DC/DC conventers/USB_5V_OUT") (pinfunction "1") (pintype "passive"))
  )
	(footprint "kria-k26-devboard-footprints:R_0402_1005Metric" (layer "F.Cu")
    (at 179.2 137.725001 180)
    (descr "Resistor SMD 0402")
    (tags "resistor SMD 0402")
    (property "Author" "Antmicro")
    (property "License" "Apache-2.0")
    (property "MPN" "CR0402-FX-1001GLF")
    (property "Manufacturer" "Bourns")
    (property "Sheetfile" "dc-dc-conventers.kicad_sch")
    (property "Sheetname" "DC/DC conventers")
    (property "Tolerance" "1%")
    (property "Val" "1k")
    (property "ki_description" "1k resistor in 0402 package with 1% tolerance")
    (attr smd)
    (fp_text reference "R142" (at 0.33 -3.194999 270) (layer "F.SilkS")
        (effects (font (size 0.7 0.7) (thickness 0.15)) (justify left bottom))
    )
    (fp_text value "R_1k_0402" (at 0 1.4 180) (layer "F.Fab") hide
        (effects (font (size 0.7 0.7) (thickness 0.15)) (justify left bottom))
    )
    (fp_text user "License: Apache-2.0" (at -0.95 5.169 180) (layer "F.Fab") hide
        (effects (font (size 0.7 0.7) (thickness 0.15)) (justify left bottom))
    )
    (fp_text user "${REFERENCE}" (at -0.95 3.168 180) (layer "F.Fab") hide
        (effects (font (size 0.7 0.7) (thickness 0.15)) (justify left bottom))
    )
    (fp_text user "Author: Antmicro" (at -0.95 4.169 180) (layer "F.Fab") hide
        (effects (font (size 0.7 0.7) (thickness 0.15)) (justify left bottom))
    )
    (fp_rect (start -0.93 -0.47) (end 0.93 0.47)
      (stroke (width 0.05) (type solid)) (fill none) (layer "F.CrtYd"))
    (fp_rect (start -0.5 -0.25) (end 0.5 0.25)
      (stroke (width 0.15) (type solid)) (fill none) (layer "F.Fab"))
    (pad "1" smd roundrect (at -0.485 0 180) (size 0.59 0.64) (layers "F.Cu" "F.Paste" "F.Mask") (roundrect_rratio 0.25)
      (net 770 "/Power Supply/DC/DC conventers/PL_3V3_OUT") (pintype "passive"))
    (pad "2" smd roundrect (at 0.485 0 180) (size 0.59 0.64) (layers "F.Cu" "F.Paste" "F.Mask") (roundrect_rratio 0.25)
      (net 191 "Net-(D19-Pad1)") (pintype "passive"))
  )
	(footprint "kria-k26-devboard-footprints:USON-10_2.5x1mm_P0.5mm" (layer "F.Cu")
    (at 110.402 73.3305 90)
    (descr "USON-10 2.5x1mm_ Pitch 0.5mm")
    (tags "USON-10 2.5x1mm Pitch 0.5mm")
    (property "Author" "Antmicro")
    (property "License" "Apache-2.0")
    (property "MPN" "TPD4E05U06QDQARQ1")
    (property "Manufacturer" "Texas Instruments")
    (property "Sheetfile" "usb.kicad_sch")
    (property "Sheetname" "USB")
    (property "ki_description" "ESD protection")
    (property "ki_keywords" "SMT, DIODE, IC, TVS, ESD")
    (attr smd)
    (fp_text reference "U25" (at 0.018 -1.7 90) (layer "F.SilkS")
        (effects (font (size 0.7 0.7) (thickness 0.15)) (justify left bottom))
    )
    (fp_text value "TPD4E05U06QDQARQ1" (at 0.018 2.499 90) (layer "F.Fab")
        (effects (font (size 0.7 0.7) (thickness 0.15)) (justify left bottom))
    )
    (fp_text user "License: Apache-2.0" (at -0.802 6.9 90) (layer "F.Fab") hide
        (effects (font (size 0.7 0.7) (thickness 0.15)) (justify left bottom))
    )
    (fp_text user "${REFERENCE}" (at -0.802 4.498 90) (layer "F.Fab") hide
        (effects (font (size 0.7 0.7) (thickness 0.15)) (justify left bottom))
    )
    (fp_text user "Author: Antmicro" (at -0.802 5.7 90) (layer "F.Fab") hide
        (effects (font (size 0.7 0.7) (thickness 0.15)) (justify left bottom))
    )
    (fp_line (start 0.498 -1.401) (end -0.5 -1.401)
      (stroke (width 0.15) (type solid)) (layer "F.SilkS"))
    (fp_line (start 0.498 1.398) (end -0.5 1.398)
      (stroke (width 0.15) (type solid)) (layer "F.SilkS"))
    (fp_circle (center -0.68 -1.27) (end -0.63 -1.27)
      (stroke (width 0.15) (type solid)) (fill solid) (layer "F.SilkS"))
    (fp_rect (start -0.8 -1.5) (end 0.8 1.499)
      (stroke (width 0.05) (type solid)) (fill none) (layer "F.CrtYd"))
    (fp_line (start -0.5 -1) (end -0.5 1.249)
      (stroke (width 0.15) (type solid)) (layer "F.Fab"))
    (fp_line (start -0.5 1.249) (end 0.498 1.249)
      (stroke (width 0.15) (type solid)) (layer "F.Fab"))
    (fp_line (start -0.25 -1.25) (end -0.5 -1)
      (stroke (width 0.15) (type solid)) (layer "F.Fab"))
    (fp_line (start 0.498 -1.25) (end -0.25 -1.25)
      (stroke (width 0.15) (type solid)) (layer "F.Fab"))
    (fp_line (start 0.498 -1.25) (end 0.498 1.249)
      (stroke (width 0.15) (type solid)) (layer "F.Fab"))
    (pad "1" smd roundrect (at -0.387 -1) (size 0.25 0.55) (layers "F.Cu" "F.Paste" "F.Mask") (roundrect_rratio 0.25)
      (net 73 "/USB/USB4_RX_N") (pintype "passive"))
    (pad "2" smd roundrect (at -0.387 -0.5) (size 0.25 0.55) (layers "F.Cu" "F.Paste" "F.Mask") (roundrect_rratio 0.25)
      (net 74 "/USB/USB4_RX_P") (pintype "passive"))
    (pad "3" smd roundrect (at -0.387 0) (size 0.4 0.55) (layers "F.Cu" "F.Paste" "F.Mask") (roundrect_rratio 0.25)
      (net 1 "GND") (pintype "power_in"))
    (pad "4" smd roundrect (at -0.387 0.498) (size 0.25 0.55) (layers "F.Cu" "F.Paste" "F.Mask") (roundrect_rratio 0.25)
      (net 284 "/USB/USB4_TX_C_N") (pintype "passive"))
    (pad "5" smd roundrect (at -0.387 0.998) (size 0.25 0.55) (layers "F.Cu" "F.Paste" "F.Mask") (roundrect_rratio 0.25)
      (net 285 "/USB/USB4_TX_C_P") (pintype "passive"))
    (pad "6" smd roundrect (at 0.385 0.998) (size 0.25 0.55) (layers "F.Cu" "F.Paste" "F.Mask") (roundrect_rratio 0.25)
      (net 285 "/USB/USB4_TX_C_P") (pintype "passive"))
    (pad "7" smd roundrect (at 0.385 0.498) (size 0.25 0.55) (layers "F.Cu" "F.Paste" "F.Mask") (roundrect_rratio 0.25)
      (net 284 "/USB/USB4_TX_C_N") (pintype "passive"))
    (pad "8" smd roundrect (at 0.385 0) (size 0.4 0.55) (layers "F.Cu" "F.Paste" "F.Mask") (roundrect_rratio 0.25)
      (net 1 "GND") (pintype "passive"))
    (pad "9" smd roundrect (at 0.385 -0.5) (size 0.25 0.55) (layers "F.Cu" "F.Paste" "F.Mask") (roundrect_rratio 0.25)
      (net 74 "/USB/USB4_RX_P") (pintype "passive"))
    (pad "10" smd roundrect (at 0.385 -1) (size 0.25 0.55) (layers "F.Cu" "F.Paste" "F.Mask") (roundrect_rratio 0.25)
      (net 73 "/USB/USB4_RX_N") (pintype "passive"))
  )
	(footprint "kria-k26-devboard-footprints:C_0805_2012Metric" (layer "F.Cu")
    (at 86.2 97.7 180)
    (descr "Capacitor SMD 0805")
    (tags "capacitor SMD 0805")
    (property "Author" "Antmicro")
    (property "Dielectric" "")
    (property "License" "Apache-2.0")
    (property "MPN" "C0805C476M9PACTU")
    (property "Manufacturer" "KEMET")
    (property "Sheetfile" "k26_som.kicad_sch")
    (property "Sheetname" "Xilinx K26 SOM")
    (property "Val" "47u")
    (property "Voltage" "")
    (property "ki_description" " ")
    (attr smd)
    (fp_text reference "C116" (at 4.55 -0.36 180) (layer "F.SilkS")
        (effects (font (size 0.7 0.7) (thickness 0.15)) (justify left bottom))
    )
    (fp_text value "C_47u_0805" (at 0 1.947 180) (layer "F.Fab") hide
        (effects (font (size 0.7 0.7) (thickness 0.15)) (justify left bottom))
    )
    (fp_text user "Author: Antmicro" (at -1.9 5.947 180) (layer "F.Fab") hide
        (effects (font (size 0.7 0.7) (thickness 0.15)) (justify left bottom))
    )
    (fp_text user "${REFERENCE}" (at -1.9 3.947 180) (layer "F.Fab") hide
        (effects (font (size 0.7 0.7) (thickness 0.15)) (justify left bottom))
    )
    (fp_text user "License: Apache-2.0" (at -1.9 4.947 180) (layer "F.Fab") hide
        (effects (font (size 0.7 0.7) (thickness 0.15)) (justify left bottom))
    )
    (fp_line (start -0.3 -0.8) (end 0.3 -0.8)
      (stroke (width 0.15) (type solid)) (layer "F.SilkS"))
    (fp_line (start -0.3 0.8) (end 0.3 0.8)
      (stroke (width 0.15) (type solid)) (layer "F.SilkS"))
    (fp_rect (start -1.9 -0.93) (end 1.9 0.93)
      (stroke (width 0.05) (type solid)) (fill none) (layer "F.CrtYd"))
    (fp_rect (start -0.95 -0.675) (end 0.95 0.675)
      (stroke (width 0.15) (type solid)) (fill none) (layer "F.Fab"))
    (pad "1" smd rect (at -1.05 0 180) (size 1.2 1.2) (layers "F.Cu" "F.Paste" "F.Mask")
      (net 8 "SOM_5V0") (pintype "passive"))
    (pad "2" smd rect (at 1.05 0 180) (size 1.2 1.2) (layers "F.Cu" "F.Paste" "F.Mask")
      (net 1 "GND") (pintype "passive"))
  )
)
